(kicad_pcb
	(version 20260206)
	(generator "pcbnew")
	(generator_version "10.0")
	(general
		(thickness 1.6)
		(legacy_teardrops no)
	)
	(paper "A4")
	(title_block
		(title "04192023_DAF0TMB3IC0_F0TG_MB_C_brd_V02_OCP.brd")
		(comment 1 "Grand Teton / footprints 1154-1160 of 8354")
	)
	(layers
		(0 "F.Cu" signal "TOP")
		(4 "In1.Cu" signal "GND")
		(6 "In2.Cu" signal "IN1")
		(8 "In3.Cu" signal "GND1")
		(10 "In4.Cu" signal "IN2")
		(12 "In5.Cu" signal "GND2")
		(14 "In6.Cu" signal "IN3")
		(16 "In7.Cu" signal "GND3")
		(18 "In8.Cu" signal "VCC")
		(20 "In9.Cu" signal "VCC1")
		(22 "In10.Cu" signal "GND4")
		(24 "In11.Cu" signal "IN4")
		(26 "In12.Cu" signal "GND5")
		(28 "In13.Cu" signal "IN5")
		(30 "In14.Cu" signal "GND6")
		(32 "In15.Cu" signal "IN6")
		(34 "In16.Cu" signal "GND7")
		(2 "B.Cu" signal "BOTTOM")
		(9 "F.Adhes" user "F.Adhesive")
		(11 "B.Adhes" user "B.Adhesive")
		(13 "F.Paste" user "Package Geometry/Pastemask Top")
		(15 "B.Paste" user "Package Geometry/Pastemask Bottom")
		(5 "F.SilkS" user "Ref Des/Silkscreen Top")
		(7 "B.SilkS" user "Ref Des/Silkscreen Bottom")
		(1 "F.Mask" user "Board Geometry/Soldermask Top")
		(3 "B.Mask" user "Board Geometry/Soldermask Bottom")
		(17 "Dwgs.User" user "User.Drawings")
		(19 "Cmts.User" user "User.Comments")
		(21 "Eco1.User" user "User.Eco1")
		(23 "Eco2.User" user "User.Eco2")
		(25 "Edge.Cuts" user "Board Geometry/Outline")
		(27 "Margin" user)
		(31 "F.CrtYd" user "Package Geometry/Place Bound Top")
		(29 "B.CrtYd" user "Package Geometry/Place Bound Bottom")
		(35 "F.Fab" user "Ref Des/Assembly Top")
		(33 "B.Fab" user "Ref Des/Assembly Bottom")
	)
	(footprint ""
		(layer "F.Cu")
		(at 271.085056 -121.83237)
		(property "Reference" "R3704"
			(at 0 0 0)
			(layer "F.SilkS")
			(hide yes)
			(effects
				(font
					(size 1.27 1.27)
				)
			)
		)
		(property "Value" ""
			(at 0 0 0)
			(layer "F.Fab")
			(effects
				(font
					(size 1.27 1.27)
				)
			)
		)
		(duplicate_pad_numbers_are_jumpers no)
		(fp_line
			(start -0.7874 -0.4064)
			(end 0.7874 -0.4064)
			(stroke
				(width 0.1524)
				(type default)
			)
			(layer "F.SilkS")
		)
		(fp_line
			(start -0.7874 0.4064)
			(end -0.7874 -0.4064)
			(stroke
				(width 0.1524)
				(type default)
			)
			(layer "F.SilkS")
		)
		(fp_line
			(start 0.7874 -0.4064)
			(end 0.7874 0.4064)
			(stroke
				(width 0.1524)
				(type default)
			)
			(layer "F.SilkS")
		)
		(fp_line
			(start 0.7874 0.4064)
			(end -0.7874 0.4064)
			(stroke
				(width 0.1524)
				(type default)
			)
			(layer "F.SilkS")
		)
		(fp_line
			(start -0.67945 -0.305054)
			(end -0.12065 -0.305054)
			(stroke
				(width 0.1)
				(type default)
			)
			(layer "F.Fab")
		)
		(fp_line
			(start -0.67945 0.3048)
			(end -0.67945 -0.305054)
			(stroke
				(width 0.1)
				(type default)
			)
			(layer "F.Fab")
		)
		(fp_line
			(start -0.12065 -0.305054)
			(end -0.12065 -0.2794)
			(stroke
				(width 0.1)
				(type default)
			)
			(layer "F.Fab")
		)
		(fp_line
			(start -0.12065 -0.2794)
			(end 0.12065 -0.2794)
			(stroke
				(width 0.1)
				(type default)
			)
			(layer "F.Fab")
		)
		(fp_line
			(start -0.12065 0.2794)
			(end -0.12065 0.3048)
			(stroke
				(width 0.1)
				(type default)
			)
			(layer "F.Fab")
		)
		(fp_line
			(start -0.12065 0.3048)
			(end -0.67945 0.3048)
			(stroke
				(width 0.1)
				(type default)
			)
			(layer "F.Fab")
		)
		(fp_line
			(start 0.120396 0.2794)
			(end -0.12065 0.2794)
			(stroke
				(width 0.1)
				(type default)
			)
			(layer "F.Fab")
		)
		(fp_line
			(start 0.120396 0.3048)
			(end 0.120396 0.2794)
			(stroke
				(width 0.1)
				(type default)
			)
			(layer "F.Fab")
		)
		(fp_line
			(start 0.12065 -0.3048)
			(end 0.67945 -0.3048)
			(stroke
				(width 0.1)
				(type default)
			)
			(layer "F.Fab")
		)
		(fp_line
			(start 0.12065 -0.2794)
			(end 0.12065 -0.3048)
			(stroke
				(width 0.1)
				(type default)
			)
			(layer "F.Fab")
		)
		(fp_line
			(start 0.67945 -0.3048)
			(end 0.67945 0.3048)
			(stroke
				(width 0.1)
				(type default)
			)
			(layer "F.Fab")
		)
		(fp_line
			(start 0.67945 0.3048)
			(end 0.120396 0.3048)
			(stroke
				(width 0.1)
				(type default)
			)
			(layer "F.Fab")
		)
		(pad "1" smd circle
			(at -0.40005 0)
			(size 0 0)
			(layers "F.Cu" "F.Mask" "F.Paste")
			(net "PCA9548_PCIE0_ADDR2")
		)
		(pad "2" smd circle
			(at 0.40005 0)
			(size 0 0)
			(layers "F.Cu" "F.Mask" "F.Paste")
			(net "GND")
		)
	)
	(footprint ""
		(layer "F.Cu")
		(at 442.419486 -22.673056 180)
		(property "Reference" "C1111"
			(at 0 0 180)
			(layer "F.SilkS")
			(hide yes)
			(effects
				(font
					(size 1.27 1.27)
				)
			)
		)
		(property "Value" ""
			(at 0 0 180)
			(layer "F.Fab")
			(effects
				(font
					(size 1.27 1.27)
				)
			)
		)
		(duplicate_pad_numbers_are_jumpers no)
		(fp_line
			(start 0.7874 0.4064)
			(end -0.7874 0.4064)
			(stroke
				(width 0.1524)
				(type default)
			)
			(layer "F.SilkS")
		)
		(fp_line
			(start 0.7874 -0.4064)
			(end 0.7874 0.4064)
			(stroke
				(width 0.1524)
				(type default)
			)
			(layer "F.SilkS")
		)
		(fp_line
			(start -0.7874 0.4064)
			(end -0.7874 -0.4064)
			(stroke
				(width 0.1524)
				(type default)
			)
			(layer "F.SilkS")
		)
		(fp_line
			(start -0.7874 -0.4064)
			(end 0.7874 -0.4064)
			(stroke
				(width 0.1524)
				(type default)
			)
			(layer "F.SilkS")
		)
		(fp_line
			(start 0.67945 0.3048)
			(end 0.120396 0.3048)
			(stroke
				(width 0.1)
				(type default)
			)
			(layer "F.Fab")
		)
		(fp_line
			(start 0.67945 -0.3048)
			(end 0.67945 0.3048)
			(stroke
				(width 0.1)
				(type default)
			)
			(layer "F.Fab")
		)
		(fp_line
			(start 0.12065 -0.2794)
			(end 0.12065 -0.3048)
			(stroke
				(width 0.1)
				(type default)
			)
			(layer "F.Fab")
		)
		(fp_line
			(start 0.12065 -0.3048)
			(end 0.67945 -0.3048)
			(stroke
				(width 0.1)
				(type default)
			)
			(layer "F.Fab")
		)
		(fp_line
			(start 0.120396 0.3048)
			(end 0.120396 0.2794)
			(stroke
				(width 0.1)
				(type default)
			)
			(layer "F.Fab")
		)
		(fp_line
			(start 0.120396 0.2794)
			(end -0.12065 0.2794)
			(stroke
				(width 0.1)
				(type default)
			)
			(layer "F.Fab")
		)
		(fp_line
			(start -0.12065 0.3048)
			(end -0.67945 0.3048)
			(stroke
				(width 0.1)
				(type default)
			)
			(layer "F.Fab")
		)
		(fp_line
			(start -0.12065 0.2794)
			(end -0.12065 0.3048)
			(stroke
				(width 0.1)
				(type default)
			)
			(layer "F.Fab")
		)
		(fp_line
			(start -0.12065 -0.2794)
			(end 0.12065 -0.2794)
			(stroke
				(width 0.1)
				(type default)
			)
			(layer "F.Fab")
		)
		(fp_line
			(start -0.12065 -0.305054)
			(end -0.12065 -0.2794)
			(stroke
				(width 0.1)
				(type default)
			)
			(layer "F.Fab")
		)
		(fp_line
			(start -0.67945 0.3048)
			(end -0.67945 -0.305054)
			(stroke
				(width 0.1)
				(type default)
			)
			(layer "F.Fab")
		)
		(fp_line
			(start -0.67945 -0.305054)
			(end -0.12065 -0.305054)
			(stroke
				(width 0.1)
				(type default)
			)
			(layer "F.Fab")
		)
		(pad "1" smd circle
			(at -0.40005 0 180)
			(size 0 0)
			(layers "F.Cu" "F.Mask" "F.Paste")
			(net "VSENSE_P12V_INA230_6_INP")
		)
		(pad "2" smd circle
			(at 0.40005 0 180)
			(size 0 0)
			(layers "F.Cu" "F.Mask" "F.Paste")
			(net "VSENSE_P12V_INA230_6_INN")
		)
	)
	(footprint ""
		(layer "F.Cu")
		(at 445.753744 -21.693378)
		(property "Reference" "PC2092"
			(at 0 0 0)
			(layer "F.SilkS")
			(hide yes)
			(effects
				(font
					(size 1.27 1.27)
				)
			)
		)
		(property "Value" ""
			(at 0 0 0)
			(layer "F.Fab")
			(effects
				(font
					(size 1.27 1.27)
				)
			)
		)
		(duplicate_pad_numbers_are_jumpers no)
		(fp_line
			(start -0.7874 -0.4064)
			(end 0.7874 -0.4064)
			(stroke
				(width 0.1524)
				(type default)
			)
			(layer "F.SilkS")
		)
		(fp_line
			(start -0.7874 0.4064)
			(end -0.7874 -0.4064)
			(stroke
				(width 0.1524)
				(type default)
			)
			(layer "F.SilkS")
		)
		(fp_line
			(start 0.7874 -0.4064)
			(end 0.7874 0.4064)
			(stroke
				(width 0.1524)
				(type default)
			)
			(layer "F.SilkS")
		)
		(fp_line
			(start 0.7874 0.4064)
			(end -0.7874 0.4064)
			(stroke
				(width 0.1524)
				(type default)
			)
			(layer "F.SilkS")
		)
		(fp_line
			(start -0.67945 -0.305054)
			(end -0.12065 -0.305054)
			(stroke
				(width 0.1)
				(type default)
			)
			(layer "F.Fab")
		)
		(fp_line
			(start -0.67945 0.3048)
			(end -0.67945 -0.305054)
			(stroke
				(width 0.1)
				(type default)
			)
			(layer "F.Fab")
		)
		(fp_line
			(start -0.12065 -0.305054)
			(end -0.12065 -0.2794)
			(stroke
				(width 0.1)
				(type default)
			)
			(layer "F.Fab")
		)
		(fp_line
			(start -0.12065 -0.2794)
			(end 0.12065 -0.2794)
			(stroke
				(width 0.1)
				(type default)
			)
			(layer "F.Fab")
		)
		(fp_line
			(start -0.12065 0.2794)
			(end -0.12065 0.3048)
			(stroke
				(width 0.1)
				(type default)
			)
			(layer "F.Fab")
		)
		(fp_line
			(start -0.12065 0.3048)
			(end -0.67945 0.3048)
			(stroke
				(width 0.1)
				(type default)
			)
			(layer "F.Fab")
		)
		(fp_line
			(start 0.120396 0.2794)
			(end -0.12065 0.2794)
			(stroke
				(width 0.1)
				(type default)
			)
			(layer "F.Fab")
		)
		(fp_line
			(start 0.120396 0.3048)
			(end 0.120396 0.2794)
			(stroke
				(width 0.1)
				(type default)
			)
			(layer "F.Fab")
		)
		(fp_line
			(start 0.12065 -0.3048)
			(end 0.67945 -0.3048)
			(stroke
				(width 0.1)
				(type default)
			)
			(layer "F.Fab")
		)
		(fp_line
			(start 0.12065 -0.2794)
			(end 0.12065 -0.3048)
			(stroke
				(width 0.1)
				(type default)
			)
			(layer "F.Fab")
		)
		(fp_line
			(start 0.67945 -0.3048)
			(end 0.67945 0.3048)
			(stroke
				(width 0.1)
				(type default)
			)
			(layer "F.Fab")
		)
		(fp_line
			(start 0.67945 0.3048)
			(end 0.120396 0.3048)
			(stroke
				(width 0.1)
				(type default)
			)
			(layer "F.Fab")
		)
		(pad "1" smd circle
			(at -0.40005 0)
			(size 0 0)
			(layers "F.Cu" "F.Mask" "F.Paste")
			(net "P12V_OCP_SFF")
		)
		(pad "2" smd circle
			(at 0.40005 0)
			(size 0 0)
			(layers "F.Cu" "F.Mask" "F.Paste")
			(net "GND")
		)
	)
	(footprint ""
		(layer "F.Cu")
		(at 112.705896 -370.57203 -90)
		(property "Reference" "C1540"
			(at 0 0 270)
			(layer "F.SilkS")
			(hide yes)
			(effects
				(font
					(size 1.27 1.27)
				)
			)
		)
		(property "Value" ""
			(at 0 0 270)
			(layer "F.Fab")
			(effects
				(font
					(size 1.27 1.27)
				)
			)
		)
		(duplicate_pad_numbers_are_jumpers no)
		(fp_line
			(start -0.299974 0.150114)
			(end -0.299974 -0.150114)
			(stroke
				(width 0.1)
				(type default)
			)
			(layer "F.Fab")
		)
		(fp_line
			(start 0.299974 0.150114)
			(end -0.299974 0.150114)
			(stroke
				(width 0.1)
				(type default)
			)
			(layer "F.Fab")
		)
		(fp_line
			(start -0.299974 -0.150114)
			(end 0.299974 -0.150114)
			(stroke
				(width 0.1)
				(type default)
			)
			(layer "F.Fab")
		)
		(fp_line
			(start 0.299974 -0.150114)
			(end 0.299974 0.150114)
			(stroke
				(width 0.1)
				(type default)
			)
			(layer "F.Fab")
		)
		(pad "1" smd rect
			(at -0.2667 0 270)
			(size 0.3048 0.381)
			(layers "F.Cu" "F.Mask" "F.Paste")
			(net "P5E_CPU1_P3_TX_C_DN<3>")
		)
		(pad "2" smd rect
			(at 0.2667 0 270)
			(size 0.3048 0.381)
			(layers "F.Cu" "F.Mask" "F.Paste")
			(net "P5E_CPU1_P3_TX_DN<3>")
		)
	)
	(footprint ""
		(layer "F.Cu")
		(at 212.598 -120.65 180)
		(property "Reference" "C1060"
			(at 0 0 180)
			(layer "F.SilkS")
			(hide yes)
			(effects
				(font
					(size 1.27 1.27)
				)
			)
		)
		(property "Value" ""
			(at 0 0 180)
			(layer "F.Fab")
			(effects
				(font
					(size 1.27 1.27)
				)
			)
		)
		(duplicate_pad_numbers_are_jumpers no)
		(fp_line
			(start 0.7874 0.4064)
			(end -0.7874 0.4064)
			(stroke
				(width 0.1524)
				(type default)
			)
			(layer "F.SilkS")
		)
		(fp_line
			(start 0.7874 -0.4064)
			(end 0.7874 0.4064)
			(stroke
				(width 0.1524)
				(type default)
			)
			(layer "F.SilkS")
		)
		(fp_line
			(start -0.7874 0.4064)
			(end -0.7874 -0.4064)
			(stroke
				(width 0.1524)
				(type default)
			)
			(layer "F.SilkS")
		)
		(fp_line
			(start -0.7874 -0.4064)
			(end 0.7874 -0.4064)
			(stroke
				(width 0.1524)
				(type default)
			)
			(layer "F.SilkS")
		)
		(fp_line
			(start 0.67945 0.3048)
			(end 0.120396 0.3048)
			(stroke
				(width 0.1)
				(type default)
			)
			(layer "F.Fab")
		)
		(fp_line
			(start 0.67945 -0.3048)
			(end 0.67945 0.3048)
			(stroke
				(width 0.1)
				(type default)
			)
			(layer "F.Fab")
		)
		(fp_line
			(start 0.12065 -0.2794)
			(end 0.12065 -0.3048)
			(stroke
				(width 0.1)
				(type default)
			)
			(layer "F.Fab")
		)
		(fp_line
			(start 0.12065 -0.3048)
			(end 0.67945 -0.3048)
			(stroke
				(width 0.1)
				(type default)
			)
			(layer "F.Fab")
		)
		(fp_line
			(start 0.120396 0.3048)
			(end 0.120396 0.2794)
			(stroke
				(width 0.1)
				(type default)
			)
			(layer "F.Fab")
		)
		(fp_line
			(start 0.120396 0.2794)
			(end -0.12065 0.2794)
			(stroke
				(width 0.1)
				(type default)
			)
			(layer "F.Fab")
		)
		(fp_line
			(start -0.12065 0.3048)
			(end -0.67945 0.3048)
			(stroke
				(width 0.1)
				(type default)
			)
			(layer "F.Fab")
		)
		(fp_line
			(start -0.12065 0.2794)
			(end -0.12065 0.3048)
			(stroke
				(width 0.1)
				(type default)
			)
			(layer "F.Fab")
		)
		(fp_line
			(start -0.12065 -0.2794)
			(end 0.12065 -0.2794)
			(stroke
				(width 0.1)
				(type default)
			)
			(layer "F.Fab")
		)
		(fp_line
			(start -0.12065 -0.305054)
			(end -0.12065 -0.2794)
			(stroke
				(width 0.1)
				(type default)
			)
			(layer "F.Fab")
		)
		(fp_line
			(start -0.67945 0.3048)
			(end -0.67945 -0.305054)
			(stroke
				(width 0.1)
				(type default)
			)
			(layer "F.Fab")
		)
		(fp_line
			(start -0.67945 -0.305054)
			(end -0.12065 -0.305054)
			(stroke
				(width 0.1)
				(type default)
			)
			(layer "F.Fab")
		)
		(pad "1" smd circle
			(at -0.40005 0 180)
			(size 0 0)
			(layers "F.Cu" "F.Mask" "F.Paste")
			(net "P3V3_AUX")
		)
		(pad "2" smd circle
			(at 0.40005 0 180)
			(size 0 0)
			(layers "F.Cu" "F.Mask" "F.Paste")
			(net "GND")
		)
	)
	(footprint ""
		(layer "F.Cu")
		(at 256.592324 -129.617216)
		(property "Reference" "C1102"
			(at 0 0 0)
			(layer "F.SilkS")
			(hide yes)
			(effects
				(font
					(size 1.27 1.27)
				)
			)
		)
		(property "Value" ""
			(at 0 0 0)
			(layer "F.Fab")
			(effects
				(font
					(size 1.27 1.27)
				)
			)
		)
		(duplicate_pad_numbers_are_jumpers no)
		(fp_line
			(start -0.7874 -0.4064)
			(end 0.7874 -0.4064)
			(stroke
				(width 0.1524)
				(type default)
			)
			(layer "F.SilkS")
		)
		(fp_line
			(start -0.7874 0.4064)
			(end -0.7874 -0.4064)
			(stroke
				(width 0.1524)
				(type default)
			)
			(layer "F.SilkS")
		)
		(fp_line
			(start 0.7874 -0.4064)
			(end 0.7874 0.4064)
			(stroke
				(width 0.1524)
				(type default)
			)
			(layer "F.SilkS")
		)
		(fp_line
			(start 0.7874 0.4064)
			(end -0.7874 0.4064)
			(stroke
				(width 0.1524)
				(type default)
			)
			(layer "F.SilkS")
		)
		(fp_line
			(start -0.67945 -0.305054)
			(end -0.12065 -0.305054)
			(stroke
				(width 0.1)
				(type default)
			)
			(layer "F.Fab")
		)
		(fp_line
			(start -0.67945 0.3048)
			(end -0.67945 -0.305054)
			(stroke
				(width 0.1)
				(type default)
			)
			(layer "F.Fab")
		)
		(fp_line
			(start -0.12065 -0.305054)
			(end -0.12065 -0.2794)
			(stroke
				(width 0.1)
				(type default)
			)
			(layer "F.Fab")
		)
		(fp_line
			(start -0.12065 -0.2794)
			(end 0.12065 -0.2794)
			(stroke
				(width 0.1)
				(type default)
			)
			(layer "F.Fab")
		)
		(fp_line
			(start -0.12065 0.2794)
			(end -0.12065 0.3048)
			(stroke
				(width 0.1)
				(type default)
			)
			(layer "F.Fab")
		)
		(fp_line
			(start -0.12065 0.3048)
			(end -0.67945 0.3048)
			(stroke
				(width 0.1)
				(type default)
			)
			(layer "F.Fab")
		)
		(fp_line
			(start 0.120396 0.2794)
			(end -0.12065 0.2794)
			(stroke
				(width 0.1)
				(type default)
			)
			(layer "F.Fab")
		)
		(fp_line
			(start 0.120396 0.3048)
			(end 0.120396 0.2794)
			(stroke
				(width 0.1)
				(type default)
			)
			(layer "F.Fab")
		)
		(fp_line
			(start 0.12065 -0.3048)
			(end 0.67945 -0.3048)
			(stroke
				(width 0.1)
				(type default)
			)
			(layer "F.Fab")
		)
		(fp_line
			(start 0.12065 -0.2794)
			(end 0.12065 -0.3048)
			(stroke
				(width 0.1)
				(type default)
			)
			(layer "F.Fab")
		)
		(fp_line
			(start 0.67945 -0.3048)
			(end 0.67945 0.3048)
			(stroke
				(width 0.1)
				(type default)
			)
			(layer "F.Fab")
		)
		(fp_line
			(start 0.67945 0.3048)
			(end 0.120396 0.3048)
			(stroke
				(width 0.1)
				(type default)
			)
			(layer "F.Fab")
		)
		(pad "1" smd circle
			(at -0.40005 0)
			(size 0 0)
			(layers "F.Cu" "F.Mask" "F.Paste")
			(net "PVDD18_S5_P0")
		)
		(pad "2" smd circle
			(at 0.40005 0)
			(size 0 0)
			(layers "F.Cu" "F.Mask" "F.Paste")
			(net "GND")
		)
	)
	(footprint ""
		(layer "F.Cu")
		(at 37.211 -364.109)
		(property "Reference" "PC368"
			(at 0 0 0)
			(layer "F.SilkS")
			(hide yes)
			(effects
				(font
					(size 1.27 1.27)
				)
			)
		)
		(property "Value" ""
			(at 0 0 0)
			(layer "F.Fab")
			(effects
				(font
					(size 1.27 1.27)
				)
			)
		)
		(duplicate_pad_numbers_are_jumpers no)
		(fp_line
			(start -0.7874 -0.4064)
			(end 0.7874 -0.4064)
			(stroke
				(width 0.1524)
				(type default)
			)
			(layer "F.SilkS")
		)
		(fp_line
			(start -0.7874 0.4064)
			(end -0.7874 -0.4064)
			(stroke
				(width 0.1524)
				(type default)
			)
			(layer "F.SilkS")
		)
		(fp_line
			(start 0.7874 -0.4064)
			(end 0.7874 0.4064)
			(stroke
				(width 0.1524)
				(type default)
			)
			(layer "F.SilkS")
		)
		(fp_line
			(start 0.7874 0.4064)
			(end -0.7874 0.4064)
			(stroke
				(width 0.1524)
				(type default)
			)
			(layer "F.SilkS")
		)
		(fp_line
			(start -0.67945 -0.305054)
			(end -0.12065 -0.305054)
			(stroke
				(width 0.1)
				(type default)
			)
			(layer "F.Fab")
		)
		(fp_line
			(start -0.67945 0.3048)
			(end -0.67945 -0.305054)
			(stroke
				(width 0.1)
				(type default)
			)
			(layer "F.Fab")
		)
		(fp_line
			(start -0.12065 -0.305054)
			(end -0.12065 -0.2794)
			(stroke
				(width 0.1)
				(type default)
			)
			(layer "F.Fab")
		)
		(fp_line
			(start -0.12065 -0.2794)
			(end 0.12065 -0.2794)
			(stroke
				(width 0.1)
				(type default)
			)
			(layer "F.Fab")
		)
		(fp_line
			(start -0.12065 0.2794)
			(end -0.12065 0.3048)
			(stroke
				(width 0.1)
				(type default)
			)
			(layer "F.Fab")
		)
		(fp_line
			(start -0.12065 0.3048)
			(end -0.67945 0.3048)
			(stroke
				(width 0.1)
				(type default)
			)
			(layer "F.Fab")
		)
		(fp_line
			(start 0.120396 0.2794)
			(end -0.12065 0.2794)
			(stroke
				(width 0.1)
				(type default)
			)
			(layer "F.Fab")
		)
		(fp_line
			(start 0.120396 0.3048)
			(end 0.120396 0.2794)
			(stroke
				(width 0.1)
				(type default)
			)
			(layer "F.Fab")
		)
		(fp_line
			(start 0.12065 -0.3048)
			(end 0.67945 -0.3048)
			(stroke
				(width 0.1)
				(type default)
			)
			(layer "F.Fab")
		)
		(fp_line
			(start 0.12065 -0.2794)
			(end 0.12065 -0.3048)
			(stroke
				(width 0.1)
				(type default)
			)
			(layer "F.Fab")
		)
		(fp_line
			(start 0.67945 -0.3048)
			(end 0.67945 0.3048)
			(stroke
				(width 0.1)
				(type default)
			)
			(layer "F.Fab")
		)
		(fp_line
			(start 0.67945 0.3048)
			(end 0.120396 0.3048)
			(stroke
				(width 0.1)
				(type default)
			)
			(layer "F.Fab")
		)
		(pad "1" smd circle
			(at -0.40005 0)
			(size 0 0)
			(layers "F.Cu" "F.Mask" "F.Paste")
			(net "PVDDCR_CPU1_P1_TEMP0")
		)
		(pad "2" smd circle
			(at 0.40005 0)
			(size 0 0)
			(layers "F.Cu" "F.Mask" "F.Paste")
			(net "GND")
		)
	)
)
